# SCM (Grand Teton) — schematic netlist excerpt (pin names and nets, part order shuffled) for the footprints in the layout excerpt that follows; sources: Cadence DE-HDL packaged netlist, KiCad conversion of 12092022_DA0F0TMDCD0_F0T_Management_Board_D_brd_V3_OCP.brd

R7  Q_RES  60.4 1% CHIP  pkg 0402LF  page 20 : A = M_BMC_DDR4_MCLK_DN ; B = M_BMC_DDR4_MCLK_C
R84  Q_RES  0 5% CHIP  pkg 0402LF  page 23 : A = V_VGAVS_BUF_R ; B = V_VGAVS_BUF

(kicad_pcb
	(version 20260206)
	(generator "pcbnew")
	(generator_version "10.0")
	(general
		(thickness 1.6)
		(legacy_teardrops no)
	)
	(paper "A4")
	(title_block
		(title "12092022_DA0F0TMDCD0_F0T_Management_Board_D_brd_V3_OCP.brd")
		(comment 1 "Grand Teton / footprints 893-894 of 1440")
	)
	(layers
		(0 "F.Cu" signal "TOP")
		(4 "In1.Cu" signal "GND")
		(6 "In2.Cu" signal "IN1")
		(8 "In3.Cu" signal "GND1")
		(10 "In4.Cu" signal "IN2")
		(12 "In5.Cu" signal "VCC")
		(14 "In6.Cu" signal "VCC1")
		(16 "In7.Cu" signal "IN3")
		(18 "In8.Cu" signal "GND2")
		(20 "In9.Cu" signal "IN4")
		(22 "In10.Cu" signal "GND3")
		(2 "B.Cu" signal "BOTTOM")
		(9 "F.Adhes" user "F.Adhesive")
		(11 "B.Adhes" user "B.Adhesive")
		(13 "F.Paste" user "Package Geometry/Pastemask Top")
		(15 "B.Paste" user "Package Geometry/Pastemask Bottom")
		(5 "F.SilkS" user "Ref Des/Silkscreen Top")
		(7 "B.SilkS" user "Ref Des/Silkscreen Bottom")
		(1 "F.Mask" user "Board Geometry/Soldermask Top")
		(3 "B.Mask" user "Board Geometry/Soldermask Bottom")
		(17 "Dwgs.User" user "User.Drawings")
		(19 "Cmts.User" user "User.Comments")
		(21 "Eco1.User" user "User.Eco1")
		(23 "Eco2.User" user "User.Eco2")
		(25 "Edge.Cuts" user "Board Geometry/Outline")
		(27 "Margin" user)
		(31 "F.CrtYd" user "Package Geometry/Place Bound Top")
		(29 "B.CrtYd" user "Package Geometry/Place Bound Bottom")
		(35 "F.Fab" user "Ref Des/Assembly Top")
		(33 "B.Fab" user "Ref Des/Assembly Bottom")
	)
	(footprint ""
		(layer "B.Cu")
		(at 43.053 -6.604 -90)
		(property "Reference" "R84"
			(at 0 0 90)
			(layer "B.SilkS")
			(hide yes)
			(effects
				(font
					(size 1.27 1.27)
				)
				(justify mirror)
			)
		)
		(property "Value" ""
			(at 0 0 90)
			(layer "B.Fab")
			(effects
				(font
					(size 1.27 1.27)
				)
				(justify mirror)
			)
		)
		(duplicate_pad_numbers_are_jumpers no)
		(fp_line
			(start -0.7874 0.4064)
			(end 0.7874 0.4064)
			(stroke
				(width 0.1524)
				(type default)
			)
			(layer "B.SilkS")
		)
		(fp_line
			(start 0.7874 0.4064)
			(end 0.7874 -0.4064)
			(stroke
				(width 0.1524)
				(type default)
			)
			(layer "B.SilkS")
		)
		(fp_line
			(start -0.7874 -0.4064)
			(end -0.7874 0.4064)
			(stroke
				(width 0.1524)
				(type default)
			)
			(layer "B.SilkS")
		)
		(fp_line
			(start 0.7874 -0.4064)
			(end -0.7874 -0.4064)
			(stroke
				(width 0.1524)
				(type default)
			)
			(layer "B.SilkS")
		)
		(fp_line
			(start -0.67945 0.3048)
			(end -0.120396 0.3048)
			(stroke
				(width 0.1)
				(type default)
			)
			(layer "B.Fab")
		)
		(fp_line
			(start -0.120396 0.3048)
			(end -0.120396 0.2794)
			(stroke
				(width 0.1)
				(type default)
			)
			(layer "B.Fab")
		)
		(fp_line
			(start 0.12065 0.3048)
			(end 0.67945 0.3048)
			(stroke
				(width 0.1)
				(type default)
			)
			(layer "B.Fab")
		)
		(fp_line
			(start 0.67945 0.3048)
			(end 0.67945 -0.305054)
			(stroke
				(width 0.1)
				(type default)
			)
			(layer "B.Fab")
		)
		(fp_line
			(start -0.120396 0.2794)
			(end 0.12065 0.2794)
			(stroke
				(width 0.1)
				(type default)
			)
			(layer "B.Fab")
		)
		(fp_line
			(start 0.12065 0.2794)
			(end 0.12065 0.3048)
			(stroke
				(width 0.1)
				(type default)
			)
			(layer "B.Fab")
		)
		(fp_line
			(start -0.12065 -0.2794)
			(end -0.12065 -0.3048)
			(stroke
				(width 0.1)
				(type default)
			)
			(layer "B.Fab")
		)
		(fp_line
			(start 0.12065 -0.2794)
			(end -0.12065 -0.2794)
			(stroke
				(width 0.1)
				(type default)
			)
			(layer "B.Fab")
		)
		(fp_line
			(start -0.67945 -0.3048)
			(end -0.67945 0.3048)
			(stroke
				(width 0.1)
				(type default)
			)
			(layer "B.Fab")
		)
		(fp_line
			(start -0.12065 -0.3048)
			(end -0.67945 -0.3048)
			(stroke
				(width 0.1)
				(type default)
			)
			(layer "B.Fab")
		)
		(fp_line
			(start 0.12065 -0.305054)
			(end 0.12065 -0.2794)
			(stroke
				(width 0.1)
				(type default)
			)
			(layer "B.Fab")
		)
		(fp_line
			(start 0.67945 -0.305054)
			(end 0.12065 -0.305054)
			(stroke
				(width 0.1)
				(type default)
			)
			(layer "B.Fab")
		)
		(pad "1" smd circle
			(at 0.40005 0 90)
			(size 0 0)
			(layers "B.Cu" "B.Mask" "B.Paste")
			(net "V_VGAVS_BUF_R")
		)
		(pad "2" smd circle
			(at -0.40005 0 90)
			(size 0 0)
			(layers "B.Cu" "B.Mask" "B.Paste")
			(net "V_VGAVS_BUF")
		)
	)
	(footprint ""
		(layer "B.Cu")
		(at 76.982828 -46.19879)
		(property "Reference" "R7"
			(at 0 0 0)
			(layer "B.SilkS")
			(hide yes)
			(effects
				(font
					(size 1.27 1.27)
				)
				(justify mirror)
			)
		)
		(property "Value" ""
			(at 0 0 0)
			(layer "B.Fab")
			(effects
				(font
					(size 1.27 1.27)
				)
				(justify mirror)
			)
		)
		(duplicate_pad_numbers_are_jumpers no)
		(fp_line
			(start -0.7874 -0.4064)
			(end -0.7874 0.4064)
			(stroke
				(width 0.1524)
				(type default)
			)
			(layer "B.SilkS")
		)
		(fp_line
			(start -0.7874 0.4064)
			(end 0.7874 0.4064)
			(stroke
				(width 0.1524)
				(type default)
			)
			(layer "B.SilkS")
		)
		(fp_line
			(start 0.487172 -0.4064)
			(end -0.7874 -0.4064)
			(stroke
				(width 0.1524)
				(type default)
			)
			(layer "B.SilkS")
		)
		(fp_line
			(start 0.7874 0.4064)
			(end 0.7874 -0.02921)
			(stroke
				(width 0.1524)
				(type default)
			)
			(layer "B.SilkS")
		)
		(fp_line
			(start -0.67945 -0.3048)
			(end -0.67945 0.3048)
			(stroke
				(width 0.1)
				(type default)
			)
			(layer "B.Fab")
		)
		(fp_line
			(start -0.67945 0.3048)
			(end -0.120396 0.3048)
			(stroke
				(width 0.1)
				(type default)
			)
			(layer "B.Fab")
		)
		(fp_line
			(start -0.12065 -0.3048)
			(end -0.67945 -0.3048)
			(stroke
				(width 0.1)
				(type default)
			)
			(layer "B.Fab")
		)
		(fp_line
			(start -0.12065 -0.2794)
			(end -0.12065 -0.3048)
			(stroke
				(width 0.1)
				(type default)
			)
			(layer "B.Fab")
		)
		(fp_line
			(start -0.120396 0.2794)
			(end 0.12065 0.2794)
			(stroke
				(width 0.1)
				(type default)
			)
			(layer "B.Fab")
		)
		(fp_line
			(start -0.120396 0.3048)
			(end -0.120396 0.2794)
			(stroke
				(width 0.1)
				(type default)
			)
			(layer "B.Fab")
		)
		(fp_line
			(start 0.12065 -0.305054)
			(end 0.12065 -0.2794)
			(stroke
				(width 0.1)
				(type default)
			)
			(layer "B.Fab")
		)
		(fp_line
			(start 0.12065 -0.2794)
			(end -0.12065 -0.2794)
			(stroke
				(width 0.1)
				(type default)
			)
			(layer "B.Fab")
		)
		(fp_line
			(start 0.12065 0.2794)
			(end 0.12065 0.3048)
			(stroke
				(width 0.1)
				(type default)
			)
			(layer "B.Fab")
		)
		(fp_line
			(start 0.12065 0.3048)
			(end 0.67945 0.3048)
			(stroke
				(width 0.1)
				(type default)
			)
			(layer "B.Fab")
		)
		(fp_line
			(start 0.67945 -0.305054)
			(end 0.12065 -0.305054)
			(stroke
				(width 0.1)
				(type default)
			)
			(layer "B.Fab")
		)
		(fp_line
			(start 0.67945 0.3048)
			(end 0.67945 -0.305054)
			(stroke
				(width 0.1)
				(type default)
			)
			(layer "B.Fab")
		)
		(pad "1" smd circle
			(at 0.40005 0 180)
			(size 0 0)
			(layers "B.Cu" "B.Mask" "B.Paste")
			(net "M_BMC_DDR4_MCLK_DN")
		)
		(pad "2" smd circle
			(at -0.40005 0 180)
			(size 0 0)
			(layers "B.Cu" "B.Mask" "B.Paste")
			(net "M_BMC_DDR4_MCLK_C")
		)
	)
)
